(kicad_pcb
	(version 20260206)
	(generator "pcbnew")
	(generator_version "10.0")
	(general
		(thickness 1.6)
		(legacy_teardrops no)
	)
	(paper "A4")
	(title_block
		(title "01162023_DA0F0TEBIF0_F0T_Expander_BD_F_brd_V02_OCP.brd")
		(comment 1 "Grand Teton / footprints 9072-9079 of 9728")
	)
	(layers
		(0 "F.Cu" signal "TOP")
		(4 "In1.Cu" signal "GND")
		(6 "In2.Cu" signal "VCC")
		(8 "In3.Cu" signal "VCC1")
		(10 "In4.Cu" signal "GND1")
		(12 "In5.Cu" signal "IN1")
		(14 "In6.Cu" signal "GND2")
		(16 "In7.Cu" signal "IN2")
		(18 "In8.Cu" signal "GND3")
		(20 "In9.Cu" signal "IN3")
		(22 "In10.Cu" signal "GND4")
		(24 "In11.Cu" signal "IN4")
		(26 "In12.Cu" signal "GND5")
		(28 "In13.Cu" signal "IN5")
		(30 "In14.Cu" signal "GND6")
		(32 "In15.Cu" signal "IN6")
		(34 "In16.Cu" signal "GND7")
		(2 "B.Cu" signal "BOTTOM")
		(9 "F.Adhes" user "F.Adhesive")
		(11 "B.Adhes" user "B.Adhesive")
		(13 "F.Paste" user "Package Geometry/Pastemask Top")
		(15 "B.Paste" user "Package Geometry/Pastemask Bottom")
		(5 "F.SilkS" user "Ref Des/Silkscreen Top")
		(7 "B.SilkS" user "Ref Des/Silkscreen Bottom")
		(1 "F.Mask" user "Board Geometry/Soldermask Top")
		(3 "B.Mask" user "Board Geometry/Soldermask Bottom")
		(17 "Dwgs.User" user "User.Drawings")
		(19 "Cmts.User" user "User.Comments")
		(21 "Eco1.User" user "User.Eco1")
		(23 "Eco2.User" user "User.Eco2")
		(25 "Edge.Cuts" user "Board Geometry/Outline")
		(27 "Margin" user)
		(31 "F.CrtYd" user "Package Geometry/Place Bound Top")
		(29 "B.CrtYd" user "Package Geometry/Place Bound Bottom")
		(35 "F.Fab" user "Ref Des/Assembly Top")
		(33 "B.Fab" user "Ref Des/Assembly Bottom")
	)
	(footprint ""
		(layer "B.Cu")
		(at 413.670242 -296.37482)
		(property "Reference" "C1878"
			(at 0 0 0)
			(layer "B.SilkS")
			(hide yes)
			(effects
				(font
					(size 1.27 1.27)
				)
				(justify mirror)
			)
		)
		(property "Value" ""
			(at 0 0 0)
			(layer "B.Fab")
			(effects
				(font
					(size 1.27 1.27)
				)
				(justify mirror)
			)
		)
		(duplicate_pad_numbers_are_jumpers no)
		(fp_line
			(start -0.299974 -0.150114)
			(end -0.299974 0.150114)
			(stroke
				(width 0.1)
				(type default)
			)
			(layer "B.Fab")
		)
		(fp_line
			(start -0.299974 0.150114)
			(end 0.299974 0.150114)
			(stroke
				(width 0.1)
				(type default)
			)
			(layer "B.Fab")
		)
		(fp_line
			(start 0.299974 -0.150114)
			(end -0.299974 -0.150114)
			(stroke
				(width 0.1)
				(type default)
			)
			(layer "B.Fab")
		)
		(fp_line
			(start 0.299974 0.150114)
			(end 0.299974 -0.150114)
			(stroke
				(width 0.1)
				(type default)
			)
			(layer "B.Fab")
		)
		(pad "1" smd rect
			(at 0.2667 0 180)
			(size 0.3048 0.381)
			(layers "B.Cu" "B.Mask" "B.Paste")
			(net "P0V8_PEX3")
		)
		(pad "2" smd rect
			(at -0.2667 0 180)
			(size 0.3048 0.381)
			(layers "B.Cu" "B.Mask" "B.Paste")
			(net "GND")
		)
	)
	(footprint ""
		(layer "B.Cu")
		(at 102.900734 -237.306612 -90)
		(property "Reference" "PC1004"
			(at 0 0 90)
			(layer "B.SilkS")
			(hide yes)
			(effects
				(font
					(size 1.27 1.27)
				)
				(justify mirror)
			)
		)
		(property "Value" ""
			(at 0 0 90)
			(layer "B.Fab")
			(effects
				(font
					(size 1.27 1.27)
				)
				(justify mirror)
			)
		)
		(duplicate_pad_numbers_are_jumpers no)
		(fp_line
			(start -1.524 0.762)
			(end 1.524 0.762)
			(stroke
				(width 0.1524)
				(type default)
			)
			(layer "B.SilkS")
		)
		(fp_line
			(start 1.524 0.762)
			(end 1.524 -0.762)
			(stroke
				(width 0.1524)
				(type default)
			)
			(layer "B.SilkS")
		)
		(fp_line
			(start -1.524 -0.762)
			(end -1.524 0.762)
			(stroke
				(width 0.1524)
				(type default)
			)
			(layer "B.SilkS")
		)
		(fp_line
			(start 1.524 -0.762)
			(end -1.524 -0.762)
			(stroke
				(width 0.1524)
				(type default)
			)
			(layer "B.SilkS")
		)
		(fp_line
			(start -1.1049 0.724916)
			(end -1.1049 -0.724916)
			(stroke
				(width 0.1)
				(type default)
			)
			(layer "B.Fab")
		)
		(fp_line
			(start 1.1049 0.724916)
			(end -1.1049 0.724916)
			(stroke
				(width 0.1)
				(type default)
			)
			(layer "B.Fab")
		)
		(fp_line
			(start -1.1049 -0.724916)
			(end 1.1049 -0.724916)
			(stroke
				(width 0.1)
				(type default)
			)
			(layer "B.Fab")
		)
		(fp_line
			(start 1.1049 -0.724916)
			(end 1.1049 0.724916)
			(stroke
				(width 0.1)
				(type default)
			)
			(layer "B.Fab")
		)
		(pad "1" smd rect
			(at 0.889 0 270)
			(size 1.016 1.27)
			(layers "B.Cu" "B.Mask" "B.Paste")
			(net "P1V8_PEX_R")
		)
		(pad "2" smd rect
			(at -0.889 0 270)
			(size 1.016 1.27)
			(layers "B.Cu" "B.Mask" "B.Paste")
			(net "GND")
		)
	)
	(footprint ""
		(layer "B.Cu")
		(at 16.251174 -308.261766 -90)
		(property "Reference" "R841"
			(at 0 0 90)
			(layer "B.SilkS")
			(hide yes)
			(effects
				(font
					(size 1.27 1.27)
				)
				(justify mirror)
			)
		)
		(property "Value" ""
			(at 0 0 90)
			(layer "B.Fab")
			(effects
				(font
					(size 1.27 1.27)
				)
				(justify mirror)
			)
		)
		(duplicate_pad_numbers_are_jumpers no)
		(fp_line
			(start -0.7874 0.4064)
			(end 0.7874 0.4064)
			(stroke
				(width 0.1524)
				(type default)
			)
			(layer "B.SilkS")
		)
		(fp_line
			(start 0.7874 0.4064)
			(end 0.7874 -0.4064)
			(stroke
				(width 0.1524)
				(type default)
			)
			(layer "B.SilkS")
		)
		(fp_line
			(start -0.7874 -0.4064)
			(end -0.7874 0.4064)
			(stroke
				(width 0.1524)
				(type default)
			)
			(layer "B.SilkS")
		)
		(fp_line
			(start 0.7874 -0.4064)
			(end -0.7874 -0.4064)
			(stroke
				(width 0.1524)
				(type default)
			)
			(layer "B.SilkS")
		)
		(fp_line
			(start -0.67945 0.3048)
			(end -0.120396 0.3048)
			(stroke
				(width 0.1)
				(type default)
			)
			(layer "B.Fab")
		)
		(fp_line
			(start -0.120396 0.3048)
			(end -0.120396 0.2794)
			(stroke
				(width 0.1)
				(type default)
			)
			(layer "B.Fab")
		)
		(fp_line
			(start 0.12065 0.3048)
			(end 0.67945 0.3048)
			(stroke
				(width 0.1)
				(type default)
			)
			(layer "B.Fab")
		)
		(fp_line
			(start 0.67945 0.3048)
			(end 0.67945 -0.305054)
			(stroke
				(width 0.1)
				(type default)
			)
			(layer "B.Fab")
		)
		(fp_line
			(start -0.120396 0.2794)
			(end 0.12065 0.2794)
			(stroke
				(width 0.1)
				(type default)
			)
			(layer "B.Fab")
		)
		(fp_line
			(start 0.12065 0.2794)
			(end 0.12065 0.3048)
			(stroke
				(width 0.1)
				(type default)
			)
			(layer "B.Fab")
		)
		(fp_line
			(start -0.12065 -0.2794)
			(end -0.12065 -0.3048)
			(stroke
				(width 0.1)
				(type default)
			)
			(layer "B.Fab")
		)
		(fp_line
			(start 0.12065 -0.2794)
			(end -0.12065 -0.2794)
			(stroke
				(width 0.1)
				(type default)
			)
			(layer "B.Fab")
		)
		(fp_line
			(start -0.67945 -0.3048)
			(end -0.67945 0.3048)
			(stroke
				(width 0.1)
				(type default)
			)
			(layer "B.Fab")
		)
		(fp_line
			(start -0.12065 -0.3048)
			(end -0.67945 -0.3048)
			(stroke
				(width 0.1)
				(type default)
			)
			(layer "B.Fab")
		)
		(fp_line
			(start 0.12065 -0.305054)
			(end 0.12065 -0.2794)
			(stroke
				(width 0.1)
				(type default)
			)
			(layer "B.Fab")
		)
		(fp_line
			(start 0.67945 -0.305054)
			(end 0.12065 -0.305054)
			(stroke
				(width 0.1)
				(type default)
			)
			(layer "B.Fab")
		)
		(pad "1" smd circle
			(at 0.40005 0 90)
			(size 0 0)
			(layers "B.Cu" "B.Mask" "B.Paste")
			(net "P1V25_PEX0_VCC")
		)
		(pad "2" smd circle
			(at -0.40005 0 90)
			(size 0 0)
			(layers "B.Cu" "B.Mask" "B.Paste")
			(net "PWRGD_P1V25_PEX0")
		)
	)
	(footprint ""
		(layer "B.Cu")
		(at 112.025176 -325.153528 -90)
		(property "Reference" "C4204"
			(at 0 0 90)
			(layer "B.SilkS")
			(hide yes)
			(effects
				(font
					(size 1.27 1.27)
				)
				(justify mirror)
			)
		)
		(property "Value" ""
			(at 0 0 90)
			(layer "B.Fab")
			(effects
				(font
					(size 1.27 1.27)
				)
				(justify mirror)
			)
		)
		(duplicate_pad_numbers_are_jumpers no)
		(fp_line
			(start -1.2954 0.5842)
			(end 1.2954 0.5842)
			(stroke
				(width 0.1524)
				(type default)
			)
			(layer "B.SilkS")
		)
		(fp_line
			(start 1.2954 0.5842)
			(end 1.2954 -0.5842)
			(stroke
				(width 0.1524)
				(type default)
			)
			(layer "B.SilkS")
		)
		(fp_line
			(start -1.2954 -0.5842)
			(end -1.2954 0.5842)
			(stroke
				(width 0.1524)
				(type default)
			)
			(layer "B.SilkS")
		)
		(fp_line
			(start 1.2954 -0.5842)
			(end -1.2954 -0.5842)
			(stroke
				(width 0.1524)
				(type default)
			)
			(layer "B.SilkS")
		)
		(fp_line
			(start -0.8636 0.4572)
			(end 0.8636 0.4572)
			(stroke
				(width 0.1)
				(type default)
			)
			(layer "B.Fab")
		)
		(fp_line
			(start 0.8636 0.4572)
			(end 0.8636 0.4064)
			(stroke
				(width 0.1)
				(type default)
			)
			(layer "B.Fab")
		)
		(fp_line
			(start -1.1938 0.4064)
			(end -0.8636 0.4064)
			(stroke
				(width 0.1)
				(type default)
			)
			(layer "B.Fab")
		)
		(fp_line
			(start -0.8636 0.4064)
			(end -0.8636 0.4572)
			(stroke
				(width 0.1)
				(type default)
			)
			(layer "B.Fab")
		)
		(fp_line
			(start 0.8636 0.4064)
			(end 1.1938 0.4064)
			(stroke
				(width 0.1)
				(type default)
			)
			(layer "B.Fab")
		)
		(fp_line
			(start 1.1938 0.4064)
			(end 1.1938 -0.4064)
			(stroke
				(width 0.1)
				(type default)
			)
			(layer "B.Fab")
		)
		(fp_line
			(start -1.1938 -0.4064)
			(end -1.1938 0.4064)
			(stroke
				(width 0.1)
				(type default)
			)
			(layer "B.Fab")
		)
		(fp_line
			(start -0.8636 -0.4064)
			(end -1.1938 -0.4064)
			(stroke
				(width 0.1)
				(type default)
			)
			(layer "B.Fab")
		)
		(fp_line
			(start 0.8636 -0.4064)
			(end 0.8636 -0.4572)
			(stroke
				(width 0.1)
				(type default)
			)
			(layer "B.Fab")
		)
		(fp_line
			(start 1.1938 -0.4064)
			(end 0.8636 -0.4064)
			(stroke
				(width 0.1)
				(type default)
			)
			(layer "B.Fab")
		)
		(fp_line
			(start -0.8636 -0.4572)
			(end -0.8636 -0.4064)
			(stroke
				(width 0.1)
				(type default)
			)
			(layer "B.Fab")
		)
		(fp_line
			(start 0.8636 -0.4572)
			(end -0.8636 -0.4572)
			(stroke
				(width 0.1)
				(type default)
			)
			(layer "B.Fab")
		)
		(pad "1" smd rect
			(at 0.7366 0 180)
			(size 0.7112 0.8128)
			(layers "B.Cu" "B.Mask" "B.Paste")
			(net "P0V8_SERDES_VDDA_PEX0_C2")
		)
		(pad "2" smd rect
			(at -0.7366 0 180)
			(size 0.7112 0.8128)
			(layers "B.Cu" "B.Mask" "B.Paste")
			(net "GND")
		)
	)
	(footprint ""
		(layer "B.Cu")
		(at 407.460704 -305.557936 -90)
		(property "Reference" "C3466"
			(at 0 0 90)
			(layer "B.SilkS")
			(hide yes)
			(effects
				(font
					(size 1.27 1.27)
				)
				(justify mirror)
			)
		)
		(property "Value" ""
			(at 0 0 90)
			(layer "B.Fab")
			(effects
				(font
					(size 1.27 1.27)
				)
				(justify mirror)
			)
		)
		(duplicate_pad_numbers_are_jumpers no)
		(fp_line
			(start -1.2954 0.5842)
			(end 1.2954 0.5842)
			(stroke
				(width 0.1524)
				(type default)
			)
			(layer "B.SilkS")
		)
		(fp_line
			(start 1.2954 0.5842)
			(end 1.2954 -0.5842)
			(stroke
				(width 0.1524)
				(type default)
			)
			(layer "B.SilkS")
		)
		(fp_line
			(start -1.2954 -0.5842)
			(end -1.2954 0.5842)
			(stroke
				(width 0.1524)
				(type default)
			)
			(layer "B.SilkS")
		)
		(fp_line
			(start 1.2954 -0.5842)
			(end -1.2954 -0.5842)
			(stroke
				(width 0.1524)
				(type default)
			)
			(layer "B.SilkS")
		)
		(fp_line
			(start -0.8636 0.4572)
			(end 0.8636 0.4572)
			(stroke
				(width 0.1)
				(type default)
			)
			(layer "B.Fab")
		)
		(fp_line
			(start 0.8636 0.4572)
			(end 0.8636 0.4064)
			(stroke
				(width 0.1)
				(type default)
			)
			(layer "B.Fab")
		)
		(fp_line
			(start -1.1938 0.4064)
			(end -0.8636 0.4064)
			(stroke
				(width 0.1)
				(type default)
			)
			(layer "B.Fab")
		)
		(fp_line
			(start -0.8636 0.4064)
			(end -0.8636 0.4572)
			(stroke
				(width 0.1)
				(type default)
			)
			(layer "B.Fab")
		)
		(fp_line
			(start 0.8636 0.4064)
			(end 1.1938 0.4064)
			(stroke
				(width 0.1)
				(type default)
			)
			(layer "B.Fab")
		)
		(fp_line
			(start 1.1938 0.4064)
			(end 1.1938 -0.4064)
			(stroke
				(width 0.1)
				(type default)
			)
			(layer "B.Fab")
		)
		(fp_line
			(start -1.1938 -0.4064)
			(end -1.1938 0.4064)
			(stroke
				(width 0.1)
				(type default)
			)
			(layer "B.Fab")
		)
		(fp_line
			(start -0.8636 -0.4064)
			(end -1.1938 -0.4064)
			(stroke
				(width 0.1)
				(type default)
			)
			(layer "B.Fab")
		)
		(fp_line
			(start 0.8636 -0.4064)
			(end 0.8636 -0.4572)
			(stroke
				(width 0.1)
				(type default)
			)
			(layer "B.Fab")
		)
		(fp_line
			(start 1.1938 -0.4064)
			(end 0.8636 -0.4064)
			(stroke
				(width 0.1)
				(type default)
			)
			(layer "B.Fab")
		)
		(fp_line
			(start -0.8636 -0.4572)
			(end -0.8636 -0.4064)
			(stroke
				(width 0.1)
				(type default)
			)
			(layer "B.Fab")
		)
		(fp_line
			(start 0.8636 -0.4572)
			(end -0.8636 -0.4572)
			(stroke
				(width 0.1)
				(type default)
			)
			(layer "B.Fab")
		)
		(pad "1" smd rect
			(at 0.7366 0 180)
			(size 0.7112 0.8128)
			(layers "B.Cu" "B.Mask" "B.Paste")
			(net "P1V25_SERDES_VDDPLL_PEX3")
		)
		(pad "2" smd rect
			(at -0.7366 0 180)
			(size 0.7112 0.8128)
			(layers "B.Cu" "B.Mask" "B.Paste")
			(net "GND")
		)
	)
	(footprint ""
		(layer "B.Cu")
		(at 281.874722 -293.99992 -90)
		(property "Reference" "C1622"
			(at 0 0 90)
			(layer "B.SilkS")
			(hide yes)
			(effects
				(font
					(size 1.27 1.27)
				)
				(justify mirror)
			)
		)
		(property "Value" ""
			(at 0 0 90)
			(layer "B.Fab")
			(effects
				(font
					(size 1.27 1.27)
				)
				(justify mirror)
			)
		)
		(duplicate_pad_numbers_are_jumpers no)
		(fp_line
			(start -0.299974 0.150114)
			(end 0.299974 0.150114)
			(stroke
				(width 0.1)
				(type default)
			)
			(layer "B.Fab")
		)
		(fp_line
			(start 0.299974 0.150114)
			(end 0.299974 -0.150114)
			(stroke
				(width 0.1)
				(type default)
			)
			(layer "B.Fab")
		)
		(fp_line
			(start -0.299974 -0.150114)
			(end -0.299974 0.150114)
			(stroke
				(width 0.1)
				(type default)
			)
			(layer "B.Fab")
		)
		(fp_line
			(start 0.299974 -0.150114)
			(end -0.299974 -0.150114)
			(stroke
				(width 0.1)
				(type default)
			)
			(layer "B.Fab")
		)
		(pad "1" smd rect
			(at 0.2667 0 90)
			(size 0.3048 0.381)
			(layers "B.Cu" "B.Mask" "B.Paste")
			(net "P0V8_PEX2")
		)
		(pad "2" smd rect
			(at -0.2667 0 90)
			(size 0.3048 0.381)
			(layers "B.Cu" "B.Mask" "B.Paste")
			(net "GND")
		)
	)
	(footprint ""
		(layer "B.Cu")
		(at 339.693758 -221.98711 -90)
		(property "Reference" "C2089"
			(at 0 0 90)
			(layer "B.SilkS")
			(hide yes)
			(effects
				(font
					(size 1.27 1.27)
				)
				(justify mirror)
			)
		)
		(property "Value" ""
			(at 0 0 90)
			(layer "B.Fab")
			(effects
				(font
					(size 1.27 1.27)
				)
				(justify mirror)
			)
		)
		(duplicate_pad_numbers_are_jumpers no)
		(fp_line
			(start -0.69215 0.2921)
			(end 0.69215 0.2921)
			(stroke
				(width 0.1524)
				(type default)
			)
			(layer "B.SilkS")
		)
		(fp_line
			(start 0.69215 0.2921)
			(end 0.69215 -0.2921)
			(stroke
				(width 0.1524)
				(type default)
			)
			(layer "B.SilkS")
		)
		(fp_line
			(start -0.69215 -0.2921)
			(end -0.69215 0.2921)
			(stroke
				(width 0.1524)
				(type default)
			)
			(layer "B.SilkS")
		)
		(fp_line
			(start 0.69215 -0.2921)
			(end -0.69215 -0.2921)
			(stroke
				(width 0.1524)
				(type default)
			)
			(layer "B.SilkS")
		)
		(fp_line
			(start -0.51435 0.2794)
			(end 0.51435 0.2794)
			(stroke
				(width 0.1)
				(type default)
			)
			(layer "B.Fab")
		)
		(fp_line
			(start 0.51435 0.2794)
			(end 0.51435 -0.2794)
			(stroke
				(width 0.1)
				(type default)
			)
			(layer "B.Fab")
		)
		(fp_line
			(start -0.51435 -0.2794)
			(end -0.51435 0.2794)
			(stroke
				(width 0.1)
				(type default)
			)
			(layer "B.Fab")
		)
		(fp_line
			(start 0.51435 -0.2794)
			(end -0.51435 -0.2794)
			(stroke
				(width 0.1)
				(type default)
			)
			(layer "B.Fab")
		)
		(pad "1" smd circle
			(at 0.40005 0 90)
			(size 0 0)
			(layers "B.Cu" "B.Mask" "B.Paste")
			(net "P3V3_FPGA_VCCIO5")
		)
		(pad "2" smd circle
			(at -0.40005 0 90)
			(size 0 0)
			(layers "B.Cu" "B.Mask" "B.Paste")
			(net "GND")
		)
		(zone
			(layer "B.Cu")
			(hatch none 0.5)
			(connect_pads
				(clearance 0)
			)
			(min_thickness 0.25)
			(keepout
				(tracks not_allowed)
				(vias allowed)
				(pads allowed)
				(copperpour not_allowed)
				(footprints allowed)
			)
			(placement
				(enabled no)
				(sheetname "")
			)
			(fill
				(thermal_gap 0.5)
				(thermal_bridge_width 0.5)
				(island_removal_mode 0)
			)
			(polygon
				(pts
					(xy 339.606128 -221.79661) (xy 339.547962 -221.88805) (xy 339.547962 -222.08744) (xy 339.606128 -222.17761)
					(xy 339.781388 -222.17761) (xy 339.839808 -222.08744) (xy 339.839808 -221.88805) (xy 339.781642 -221.79661)
				)
			)
		)
	)
	(footprint ""
		(layer "B.Cu")
		(at 123.614434 -303.649634 -90)
		(property "Reference" "PC121"
			(at 0 0 90)
			(layer "B.SilkS")
			(hide yes)
			(effects
				(font
					(size 1.27 1.27)
				)
				(justify mirror)
			)
		)
		(property "Value" ""
			(at 0 0 90)
			(layer "B.Fab")
			(effects
				(font
					(size 1.27 1.27)
				)
				(justify mirror)
			)
		)
		(duplicate_pad_numbers_are_jumpers no)
		(fp_line
			(start -1.524 0.762)
			(end 1.524 0.762)
			(stroke
				(width 0.1524)
				(type default)
			)
			(layer "B.SilkS")
		)
		(fp_line
			(start 1.524 0.762)
			(end 1.524 -0.762)
			(stroke
				(width 0.1524)
				(type default)
			)
			(layer "B.SilkS")
		)
		(fp_line
			(start -1.524 -0.762)
			(end -1.524 0.762)
			(stroke
				(width 0.1524)
				(type default)
			)
			(layer "B.SilkS")
		)
		(fp_line
			(start 1.524 -0.762)
			(end -1.524 -0.762)
			(stroke
				(width 0.1524)
				(type default)
			)
			(layer "B.SilkS")
		)
		(fp_line
			(start -1.1049 0.724916)
			(end -1.1049 -0.724916)
			(stroke
				(width 0.1)
				(type default)
			)
			(layer "B.Fab")
		)
		(fp_line
			(start 1.1049 0.724916)
			(end -1.1049 0.724916)
			(stroke
				(width 0.1)
				(type default)
			)
			(layer "B.Fab")
		)
		(fp_line
			(start -1.1049 -0.724916)
			(end 1.1049 -0.724916)
			(stroke
				(width 0.1)
				(type default)
			)
			(layer "B.Fab")
		)
		(fp_line
			(start 1.1049 -0.724916)
			(end 1.1049 0.724916)
			(stroke
				(width 0.1)
				(type default)
			)
			(layer "B.Fab")
		)
		(pad "1" smd rect
			(at 0.889 0 270)
			(size 1.016 1.27)
			(layers "B.Cu" "B.Mask" "B.Paste")
			(net "P0V8_PEX1")
		)
		(pad "2" smd rect
			(at -0.889 0 270)
			(size 1.016 1.27)
			(layers "B.Cu" "B.Mask" "B.Paste")
			(net "GND")
		)
	)
)
